G04*
G04 #@! TF.GenerationSoftware,Altium Limited,Altium Designer,23.6.0 (18)*
G04*
G04 Layer_Physical_Order=1*
G04 Layer_Color=255*
%FSLAX44Y44*%
%MOMM*%
G71*
G04*
G04 #@! TF.SameCoordinates,B62FFF2A-40BB-47C2-B022-6C0D6E2DF31E*
G04*
G04*
G04 #@! TF.FilePolarity,Positive*
G04*
G01*
G75*
%ADD17C,0.2540*%
%ADD26R,0.5500X0.6000*%
G04:AMPARAMS|DCode=27|XSize=1.164mm|YSize=0.3358mm|CornerRadius=0.1679mm|HoleSize=0mm|Usage=FLASHONLY|Rotation=90.000|XOffset=0mm|YOffset=0mm|HoleType=Round|Shape=RoundedRectangle|*
%AMROUNDEDRECTD27*
21,1,1.1640,0.0000,0,0,90.0*
21,1,0.8281,0.3358,0,0,90.0*
1,1,0.3358,0.0000,0.4141*
1,1,0.3358,0.0000,-0.4141*
1,1,0.3358,0.0000,-0.4141*
1,1,0.3358,0.0000,0.4141*
%
%ADD27ROUNDEDRECTD27*%
%ADD28R,0.3358X1.1640*%
%ADD29R,0.8000X0.8000*%
%ADD30R,0.5500X0.5500*%
%ADD31R,0.5500X0.5500*%
%ADD32R,0.5153X0.4725*%
%ADD33R,0.3500X1.4500*%
%ADD34R,0.4500X0.5000*%
%ADD35R,1.1546X1.7062*%
%ADD36R,1.2700X0.5588*%
%ADD37R,0.6000X0.9000*%
%ADD38R,0.5000X0.6000*%
%ADD39R,0.8000X0.8000*%
%ADD40R,0.5000X0.5000*%
%ADD41R,0.5000X0.5000*%
%ADD42R,0.6000X0.5000*%
%ADD47R,1.0000X1.0500*%
%ADD48R,1.0500X2.2000*%
%ADD61C,0.1905*%
%ADD62C,0.2413*%
%ADD63C,1.0000*%
%ADD64R,0.8001X1.7983*%
%ADD65C,0.4064*%
%ADD66C,5.5000*%
G36*
X171000Y133500D02*
X165000D01*
Y82000D01*
X144000D01*
Y138000D01*
X152993D01*
Y175690D01*
X171000D01*
Y133500D01*
D02*
G37*
G36*
X215922Y50937D02*
X215354Y50617D01*
X213382Y50158D01*
X212870Y50670D01*
X211657Y51172D01*
X210343D01*
X209130Y50670D01*
X208883Y50423D01*
X206896Y50198D01*
X205800Y50582D01*
X205328Y51055D01*
X204114Y51557D01*
X202801D01*
X201587Y51055D01*
X200658Y50126D01*
X200156Y48912D01*
Y47599D01*
X200658Y46385D01*
X201587Y45456D01*
X201804Y45366D01*
D01*
X202801Y44953D01*
X203000D01*
Y43113D01*
X202244Y42799D01*
X202051Y42607D01*
D01*
X201315Y41870D01*
X200812Y40657D01*
Y39343D01*
X201315Y38130D01*
X202244Y37201D01*
X203458Y36698D01*
X204771D01*
X205862Y37150D01*
X205985Y37201D01*
X207318Y37760D01*
X209458Y36676D01*
X209639Y34243D01*
X208588Y33541D01*
X207209Y32162D01*
X207209Y32162D01*
X206767Y31500D01*
X203000D01*
Y31000D01*
X190060D01*
Y31500D01*
X189620D01*
Y61855D01*
X189895Y62130D01*
X190397Y63343D01*
Y64657D01*
X189895Y65870D01*
X188966Y66799D01*
X187752Y67302D01*
X186439D01*
X185225Y66799D01*
X184063Y66026D01*
X182902Y66799D01*
X181688Y67302D01*
X180375D01*
X179161Y66799D01*
X178232Y65870D01*
X177729Y64657D01*
Y63343D01*
X178232Y62130D01*
X179161Y61201D01*
X179484Y61067D01*
X179524Y60864D01*
X180072Y60045D01*
X180380Y59737D01*
Y31500D01*
X175948D01*
X175902Y31731D01*
X175007Y33894D01*
X174123Y35217D01*
X172467Y36872D01*
X171144Y37757D01*
X171144Y37757D01*
X168981Y38652D01*
X168981Y38653D01*
X167421Y38963D01*
X165079D01*
X163519Y38653D01*
X163519Y38652D01*
X161356Y37757D01*
X160033Y36872D01*
X158377Y35217D01*
X157493Y33894D01*
X157493Y33894D01*
X156597Y31731D01*
X156552Y31500D01*
X119766D01*
Y44158D01*
X119870Y44201D01*
X120799Y45130D01*
X121302Y46343D01*
Y47657D01*
X120799Y48870D01*
X119870Y49799D01*
X118657Y50302D01*
X117343D01*
X116130Y49799D01*
X115201Y48870D01*
X114698Y47657D01*
Y46343D01*
X115201Y45130D01*
X115234Y45096D01*
Y31500D01*
X39766D01*
Y46370D01*
X41761Y46992D01*
X42306Y47024D01*
X43130Y46201D01*
X44343Y45698D01*
X45657D01*
X46870Y46201D01*
X47799Y47130D01*
X48302Y48343D01*
Y49097D01*
X53602Y54398D01*
X54093Y55133D01*
X54266Y56000D01*
Y60230D01*
X56270D01*
Y67690D01*
X56270Y67770D01*
Y70230D01*
X56270Y70310D01*
Y77770D01*
X54266D01*
Y102061D01*
X62939Y110734D01*
X118236D01*
X120480Y110020D01*
X120480Y108194D01*
Y101980D01*
X122734D01*
Y94085D01*
X122685Y94036D01*
X122685D01*
X122230Y93270D01*
X122230Y93270D01*
X122230Y91684D01*
Y82730D01*
X132770D01*
Y93270D01*
X129621D01*
X127266Y94036D01*
Y101980D01*
X128520D01*
Y110020D01*
X125817D01*
X124765Y112560D01*
X133194Y120989D01*
X134793Y120626D01*
X135734Y120016D01*
Y79939D01*
X124497Y68702D01*
X114987D01*
X112531Y71158D01*
X112572Y71981D01*
X113312Y73969D01*
X113870Y74201D01*
X114799Y75130D01*
X115302Y76343D01*
Y77657D01*
X114799Y78870D01*
X114590Y79080D01*
Y82730D01*
X117770D01*
Y93270D01*
X107230D01*
Y82730D01*
X109410D01*
Y79080D01*
X109201Y78870D01*
X108969Y78312D01*
X106981Y77572D01*
X106158Y77531D01*
X84087Y99602D01*
X83351Y100094D01*
X82484Y100266D01*
X72000D01*
X71133Y100094D01*
X70398Y99602D01*
X64398Y93602D01*
X63906Y92867D01*
X63734Y92000D01*
Y77770D01*
X61730D01*
Y70310D01*
X61730Y70230D01*
Y67770D01*
X61730Y67690D01*
Y60230D01*
X63734D01*
Y55939D01*
X56097Y48302D01*
X55343D01*
X54130Y47799D01*
X53201Y46870D01*
X52698Y45657D01*
Y44343D01*
X53201Y43130D01*
X54130Y42201D01*
X55343Y41698D01*
X56657D01*
X57870Y42201D01*
X58799Y43130D01*
X59302Y44343D01*
Y45097D01*
X67602Y53398D01*
X68094Y54133D01*
X68266Y55000D01*
Y60230D01*
X70270D01*
Y67690D01*
X70270Y67770D01*
Y70230D01*
X70270Y70310D01*
Y77770D01*
X68266D01*
Y91061D01*
X72939Y95734D01*
X81545D01*
X112446Y64834D01*
X113181Y64343D01*
X114048Y64170D01*
X114048Y64170D01*
X125436D01*
X126303Y64343D01*
X127038Y64834D01*
X139602Y77398D01*
X140093Y78133D01*
X140266Y79000D01*
X140266Y79000D01*
Y81564D01*
X142625Y82000D01*
X143028Y81028D01*
X144000Y80625D01*
X165000D01*
X165972Y81028D01*
X166375Y82000D01*
Y86199D01*
X167285D01*
Y105801D01*
X166375D01*
Y109199D01*
X167285D01*
Y128801D01*
X166375D01*
Y132125D01*
X171000D01*
X171253Y132230D01*
X172770D01*
Y139770D01*
X172375D01*
Y144230D01*
X172770D01*
Y151770D01*
X172375D01*
Y156230D01*
X172770D01*
Y163770D01*
X172375D01*
Y167740D01*
X173262D01*
Y188263D01*
X162721D01*
Y188264D01*
X162264D01*
Y188263D01*
X153806D01*
X151723Y188263D01*
X149183Y188263D01*
X140725Y188263D01*
X138185Y188263D01*
X129726Y188263D01*
X127186Y188263D01*
X118728Y188263D01*
X116188Y188263D01*
X107730D01*
Y167740D01*
X107943D01*
X108996Y165200D01*
X104065Y160270D01*
X102753D01*
X100448Y159315D01*
X98685Y157552D01*
X97730Y155247D01*
Y152753D01*
X98685Y150448D01*
X99734Y149399D01*
Y140520D01*
X98480D01*
Y140135D01*
X95940Y139480D01*
X95870Y139549D01*
X94657Y140052D01*
X93343D01*
X93194Y139990D01*
X90767Y141329D01*
X90653Y141478D01*
Y143810D01*
X80113D01*
Y133270D01*
X80113D01*
X81503Y131876D01*
Y125416D01*
X81503Y123836D01*
X81503Y121296D01*
Y115266D01*
X62000D01*
X61133Y115093D01*
X60398Y114602D01*
X50398Y104602D01*
X49907Y103867D01*
X49734Y103000D01*
Y77770D01*
X47730D01*
Y70310D01*
X47730Y70230D01*
Y67770D01*
X47730Y67690D01*
Y60230D01*
X49734D01*
Y56939D01*
X45097Y52302D01*
X44343D01*
X43130Y51799D01*
X40455Y52639D01*
X40093Y53133D01*
X40266Y54000D01*
Y60480D01*
X42020D01*
Y68980D01*
Y77520D01*
X40590D01*
Y81920D01*
X40799Y82130D01*
X41302Y83343D01*
Y84657D01*
X40799Y85870D01*
X39870Y86799D01*
X38657Y87302D01*
X37343D01*
X36130Y86799D01*
X35201Y85870D01*
X34698Y84657D01*
Y83343D01*
X35201Y82130D01*
X35410Y81920D01*
Y77520D01*
X33980D01*
Y68980D01*
Y60480D01*
X35734D01*
Y56836D01*
X33657Y54947D01*
X32343D01*
X31130Y54444D01*
X30201Y53516D01*
X29698Y52302D01*
Y51000D01*
Y50988D01*
X30201Y49775D01*
X31000Y48976D01*
Y47956D01*
X30081Y47036D01*
D01*
X29578Y45823D01*
Y44509D01*
X30081Y43295D01*
X31000Y42376D01*
Y40670D01*
X30259Y39928D01*
D01*
X30201Y39870D01*
D01*
X29698Y38657D01*
Y37343D01*
X30201Y36130D01*
X31000Y35330D01*
Y33670D01*
X30201Y32870D01*
D01*
D01*
X29698Y31657D01*
Y31500D01*
Y30343D01*
X30201Y29130D01*
X31000Y28330D01*
Y25000D01*
X15000D01*
Y31500D01*
X13233D01*
X12791Y32162D01*
X11412Y33541D01*
X11412Y33541D01*
X10088Y34425D01*
X10088Y34425D01*
X8286Y35172D01*
X7699Y35289D01*
X7125Y35463D01*
X6150Y35559D01*
X4078Y37200D01*
Y38000D01*
Y39343D01*
X4078Y415922D01*
X215922D01*
X215922Y50937D01*
D02*
G37*
%LPC*%
G36*
X171247Y381270D02*
X168753D01*
X166448Y380315D01*
X164685Y378552D01*
X163730Y376247D01*
Y373753D01*
X164685Y371448D01*
X166448Y369685D01*
X167410Y369286D01*
Y366354D01*
X166230Y364270D01*
X163770D01*
X163690Y364270D01*
X156230D01*
Y362590D01*
X152607D01*
X151616Y362393D01*
X150776Y361831D01*
X147810Y358865D01*
X145270Y359917D01*
Y361980D01*
X145320Y362230D01*
Y364657D01*
X145360Y364698D01*
X145657D01*
X146870Y365201D01*
X147799Y366130D01*
X148302Y367343D01*
Y368657D01*
X147799Y369870D01*
X146870Y370799D01*
X145657Y371302D01*
X144343D01*
X143130Y370799D01*
X142201Y369870D01*
X141698Y368657D01*
X140842Y368395D01*
X138302Y368657D01*
X137799Y369870D01*
X136870Y370799D01*
X135657Y371302D01*
X134343D01*
X133130Y370799D01*
X132201Y369870D01*
X131698Y368657D01*
X131456Y368654D01*
X128924Y369214D01*
Y369214D01*
X113684D01*
Y361086D01*
X128924D01*
Y362560D01*
X132150D01*
X133141Y362757D01*
X133981Y363319D01*
X134190Y363527D01*
X136683Y362495D01*
X136730Y362393D01*
Y357310D01*
X136730Y357230D01*
Y354770D01*
X136730Y354690D01*
Y350892D01*
X135277Y349440D01*
X128924D01*
Y350914D01*
X113684D01*
Y342786D01*
X128924D01*
Y344260D01*
X136350D01*
X137341Y344457D01*
X138181Y345019D01*
X140393Y347230D01*
X145270D01*
Y348410D01*
X147857D01*
X148848Y348607D01*
X149688Y349169D01*
X150250Y350009D01*
X150447Y351000D01*
Y354177D01*
X153680Y357410D01*
X156230D01*
Y355730D01*
X157410D01*
Y344270D01*
X156230D01*
Y335730D01*
X163770D01*
Y344270D01*
X162590D01*
Y353646D01*
X163770Y355730D01*
X166230D01*
X166310Y355730D01*
X173770D01*
Y364270D01*
X172590D01*
Y369286D01*
X173552Y369685D01*
X175315Y371448D01*
X175714Y372410D01*
X178920D01*
X179130Y372201D01*
X180343Y371698D01*
X181657D01*
X182870Y372201D01*
X183799Y373130D01*
X184302Y374343D01*
Y375657D01*
X183799Y376870D01*
X182870Y377799D01*
X181657Y378302D01*
X180343D01*
X179130Y377799D01*
X178920Y377590D01*
X175714D01*
X175315Y378552D01*
X173552Y380315D01*
X171247Y381270D01*
D02*
G37*
G36*
X109620Y360064D02*
X94380D01*
Y357058D01*
X92793D01*
X91925Y356886D01*
X91190Y356395D01*
X81310Y346515D01*
X78770Y346866D01*
Y349770D01*
X70230D01*
Y338230D01*
X78770D01*
Y341734D01*
X82000D01*
X82867Y341907D01*
X83602Y342398D01*
X92221Y351016D01*
X94380Y351936D01*
X94380Y351936D01*
Y351936D01*
X94380Y351936D01*
X109620D01*
Y360064D01*
D02*
G37*
G36*
X40270Y390270D02*
X27730D01*
Y377230D01*
X31734D01*
Y372071D01*
X31684D01*
X32057Y368289D01*
X33160Y364652D01*
X34951Y361300D01*
X35368Y360793D01*
Y356368D01*
X36734D01*
Y351770D01*
X35230D01*
Y344310D01*
X35230Y344230D01*
Y341770D01*
X35230Y341690D01*
Y334230D01*
X36890D01*
X37106Y332034D01*
X38405Y327753D01*
X40513Y323809D01*
X43351Y320351D01*
X43351D01*
X43424Y320347D01*
X45232Y318143D01*
X46602Y315581D01*
X47446Y312800D01*
X47510Y312142D01*
X45805Y310260D01*
X44738D01*
Y289736D01*
X55279D01*
Y310260D01*
X52290D01*
X51951Y313696D01*
X50847Y317339D01*
X49052Y320695D01*
X46638Y323638D01*
X46638Y323638D01*
X45030Y325512D01*
X44333Y326361D01*
X42649Y329511D01*
X41988Y331690D01*
X42770Y334230D01*
X42770D01*
Y341690D01*
X42770Y341770D01*
Y344230D01*
X42770Y344310D01*
Y351770D01*
X41266D01*
Y356368D01*
X50632D01*
Y357734D01*
X56230D01*
Y356230D01*
X57734D01*
Y349770D01*
X55230D01*
Y338230D01*
X63770D01*
Y349770D01*
X62266D01*
Y356230D01*
X63770D01*
Y363770D01*
X56230D01*
Y362266D01*
X50632D01*
Y363632D01*
X38952D01*
X38771Y363853D01*
X37404Y366410D01*
X36562Y369185D01*
X36278Y372071D01*
X36266D01*
Y377230D01*
X40270D01*
Y390270D01*
D02*
G37*
G36*
X194270Y338770D02*
X185730D01*
Y334893D01*
X179563Y328725D01*
X178247Y329270D01*
X175753D01*
X173448Y328315D01*
X171685Y326552D01*
X170730Y324247D01*
Y321753D01*
X171128Y320791D01*
X166160Y315823D01*
X165599Y314983D01*
X165402Y313992D01*
Y312056D01*
X163606Y310260D01*
X161379D01*
X159583Y312056D01*
Y318698D01*
X159657D01*
X160870Y319201D01*
X161799Y320130D01*
X162302Y321343D01*
Y322657D01*
X161799Y323870D01*
X160870Y324799D01*
X159657Y325302D01*
X158623D01*
X158269Y325370D01*
X156270Y327192D01*
Y328247D01*
X155315Y330552D01*
X153552Y332315D01*
X151247Y333270D01*
X148753D01*
X146448Y332315D01*
X144685Y330552D01*
X143730Y328247D01*
Y325753D01*
X144685Y323448D01*
X144745Y323388D01*
X144169Y322813D01*
X143607Y321972D01*
X143410Y320981D01*
Y312056D01*
X141614Y310260D01*
X140725D01*
X138185Y310260D01*
X134657D01*
X134536Y310871D01*
X134118Y311496D01*
Y316084D01*
X134400Y316201D01*
X135329Y317130D01*
X135832Y318343D01*
Y319657D01*
X135329Y320871D01*
X134400Y321799D01*
X133187Y322302D01*
X131873D01*
X130659Y321799D01*
X129498Y321026D01*
X128336Y321799D01*
X127123Y322302D01*
X126418D01*
X125218Y323112D01*
X124270Y324414D01*
Y326247D01*
X123315Y328552D01*
X121552Y330315D01*
X119247Y331270D01*
X116753D01*
X114448Y330315D01*
X112685Y328552D01*
X112152Y327266D01*
X108770D01*
Y328270D01*
X101230D01*
Y319730D01*
X108312D01*
X109213Y319417D01*
X110735Y318341D01*
Y310260D01*
X107730D01*
Y289736D01*
X116188D01*
X118271Y289736D01*
X120811Y289736D01*
X129269D01*
Y289736D01*
X129726D01*
Y289736D01*
X138185D01*
X140267Y289736D01*
X142807Y289736D01*
X151266Y289736D01*
X153806Y289736D01*
X162264Y289736D01*
X164804Y289736D01*
X173262Y289736D01*
X175802Y289736D01*
X184260D01*
Y298410D01*
X195286D01*
X195685Y297448D01*
X197448Y295685D01*
X199753Y294730D01*
X202247D01*
X204552Y295685D01*
X206315Y297448D01*
X207270Y299753D01*
Y302247D01*
X206315Y304552D01*
X204552Y306315D01*
X202247Y307270D01*
X199753D01*
X197448Y306315D01*
X195685Y304552D01*
X195286Y303590D01*
X184260D01*
Y310260D01*
X175802D01*
X173719Y310260D01*
X172377D01*
X171767Y310870D01*
Y314105D01*
X174791Y317128D01*
X175753Y316730D01*
X178247D01*
X180552Y317685D01*
X182315Y319448D01*
X183270Y321753D01*
Y324247D01*
X183018Y324855D01*
X189393Y331230D01*
X194270D01*
Y338770D01*
D02*
G37*
G36*
X83657Y320302D02*
X82343D01*
X81130Y319799D01*
X80201Y318870D01*
X79698Y317657D01*
Y316343D01*
X80201Y315130D01*
X80413Y314917D01*
Y312056D01*
X78617Y310260D01*
X77733D01*
X75193Y310260D01*
X66734D01*
Y289736D01*
X75193D01*
X77275Y289736D01*
X79815Y289736D01*
X88274D01*
Y310260D01*
X85593D01*
Y314923D01*
X85799Y315130D01*
X86302Y316343D01*
Y317657D01*
X85799Y318870D01*
X84870Y319799D01*
X83657Y320302D01*
D02*
G37*
G36*
X77733Y188263D02*
X75193Y188263D01*
X66734Y188263D01*
X64194Y188263D01*
X55736Y188263D01*
X53196Y188263D01*
X44738D01*
Y167740D01*
X47419D01*
Y163088D01*
X47201Y162870D01*
X46698Y161657D01*
Y160343D01*
X47201Y159130D01*
X48130Y158201D01*
X49343Y157698D01*
X50657D01*
X51870Y158201D01*
X52799Y159130D01*
X53302Y160343D01*
Y161657D01*
X52799Y162870D01*
X52598Y163071D01*
Y165944D01*
X54394Y167740D01*
X55279D01*
X57819Y167740D01*
X66277Y167740D01*
X68817Y167740D01*
X77275Y167740D01*
X79815Y167740D01*
X88274D01*
Y188263D01*
X77733Y188263D01*
D02*
G37*
G36*
X90653Y158810D02*
X80113D01*
Y155806D01*
X73714D01*
X72847Y155633D01*
X72111Y155142D01*
X70124Y153155D01*
X65669D01*
X65126Y153968D01*
X64151Y154620D01*
X63000Y154848D01*
X61849Y154620D01*
X60874Y153968D01*
X60222Y152992D01*
X59993Y151842D01*
Y143560D01*
X60222Y142410D01*
X60874Y141434D01*
X61849Y140782D01*
X63000Y140553D01*
X64151Y140782D01*
X65126Y141434D01*
X65778Y142410D01*
X66007Y143560D01*
Y148623D01*
X71063D01*
X71930Y148796D01*
X72665Y149287D01*
X74652Y151274D01*
X80113D01*
Y148270D01*
X90653D01*
Y158810D01*
D02*
G37*
G36*
X39657Y150302D02*
X38343D01*
X37130Y149799D01*
X36201Y148870D01*
X36187Y148837D01*
X34227Y148025D01*
X32249Y146508D01*
D01*
X31373Y145627D01*
D01*
X29922Y143736D01*
X29011Y141534D01*
X29009Y141520D01*
X26980D01*
Y132980D01*
Y124480D01*
X28734D01*
Y123000D01*
X28907Y122133D01*
X29398Y121398D01*
X36698Y114097D01*
Y113343D01*
X37201Y112130D01*
X38130Y111201D01*
X39343Y110698D01*
X40657D01*
X41870Y111201D01*
X42799Y112130D01*
X43302Y113343D01*
Y113769D01*
X45515Y115159D01*
X45649Y115189D01*
X46698Y114407D01*
Y114343D01*
X47201Y113130D01*
X48130Y112201D01*
X49343Y111698D01*
X50657D01*
X51870Y112201D01*
X52799Y113130D01*
X53302Y114343D01*
Y115657D01*
X52799Y116870D01*
X51870Y117799D01*
X50657Y118302D01*
X49903D01*
X46193Y122012D01*
X46020Y124480D01*
X46020D01*
Y134984D01*
X53551D01*
Y125209D01*
X59449D01*
Y139389D01*
X56329D01*
X55690Y139516D01*
X46020D01*
Y141520D01*
X41036D01*
X40531Y144060D01*
X40870Y144201D01*
X41799Y145130D01*
X42302Y146343D01*
Y147657D01*
X41799Y148870D01*
X40870Y149799D01*
X39657Y150302D01*
D02*
G37*
G36*
X78657Y89302D02*
X77343D01*
X76130Y88799D01*
X75201Y87870D01*
X74698Y86657D01*
Y85343D01*
X75201Y84130D01*
X76130Y83201D01*
X77343Y82698D01*
X77410D01*
Y77520D01*
X75980D01*
Y68980D01*
Y60480D01*
X77734D01*
Y51404D01*
X77201Y50870D01*
X76698Y49657D01*
Y48343D01*
X77201Y47130D01*
X78130Y46201D01*
X79343Y45698D01*
X80657D01*
X81870Y46201D01*
X82799Y47130D01*
X83302Y48343D01*
Y49657D01*
X82799Y50870D01*
X82266Y51404D01*
Y60480D01*
X84020D01*
Y68980D01*
Y77520D01*
X82590D01*
Y84000D01*
X82393Y84991D01*
X81831Y85831D01*
X81302Y86361D01*
Y86657D01*
X80799Y87870D01*
X79870Y88799D01*
X78657Y89302D01*
D02*
G37*
%LPD*%
G36*
X41395Y344230D02*
Y341770D01*
Y341770D01*
X36605D01*
Y341770D01*
Y344230D01*
Y344230D01*
X41395D01*
Y344230D01*
D02*
G37*
D17*
X112500Y88000D02*
G03*
X112000Y86793I1207J-1207D01*
G01*
X85523Y118856D02*
X85595Y118928D01*
X101928D01*
X102000Y119000D01*
X69468Y121045D02*
X69500Y121076D01*
Y132299D01*
X146000Y320981D02*
X150000Y324981D01*
Y327000D01*
X146000Y300003D02*
Y320981D01*
X159500Y360000D02*
X160000Y359500D01*
X141000Y351000D02*
X147857D01*
X152607Y360000D02*
X159500D01*
X147857Y355249D02*
X152607Y360000D01*
X147857Y351000D02*
Y355249D01*
X63000Y26388D02*
Y38000D01*
X77500Y12750D02*
Y34000D01*
X193000Y27879D02*
Y37000D01*
X192500Y27379D02*
X193000Y27879D01*
X192500Y12750D02*
Y27379D01*
X62500Y12750D02*
Y25888D01*
X63000Y26388D01*
X78000Y86000D02*
X80000Y84000D01*
Y73250D02*
Y84000D01*
X112000Y77000D02*
Y86793D01*
X106000Y106000D02*
X115000D01*
X117000Y121000D02*
Y129250D01*
X102000Y119000D02*
Y129250D01*
X38000Y73250D02*
Y84000D01*
X83000Y317000D02*
X83003Y316997D01*
Y299998D02*
Y316997D01*
X156993Y319993D02*
X159000Y322000D01*
X156993Y299998D02*
Y319993D01*
X50000Y161000D02*
X50009Y161008D01*
Y178002D01*
X179992Y301000D02*
X201000D01*
X178990Y299998D02*
X179992Y301000D01*
X145995Y299998D02*
X146000Y300003D01*
X167992Y313992D02*
X177000Y323000D01*
X167992Y299998D02*
Y313992D01*
X177500Y323000D02*
X189500Y335000D01*
X190000D01*
X177000Y323000D02*
X177500D01*
X190000Y345000D02*
Y354000D01*
X170000Y340000D02*
X177000D01*
X170000Y375000D02*
X181000D01*
X170000Y360000D02*
Y375000D01*
X160000Y340000D02*
Y359500D01*
Y340000D02*
X160000Y340000D01*
X136350Y346850D02*
X140500Y351000D01*
X121304Y346850D02*
X136350D01*
X140500Y351000D02*
X141000D01*
X142730Y365730D02*
X145000Y368000D01*
X141500Y361000D02*
X142730Y362230D01*
X141000Y361000D02*
X141500D01*
X142730Y362230D02*
Y365730D01*
X132150Y365150D02*
X135000Y368000D01*
X121304Y365150D02*
X132150D01*
X95000Y324000D02*
Y334000D01*
X95000Y324000D02*
X95000Y324000D01*
X70000Y360000D02*
X79000D01*
X176000Y43588D02*
X177500Y42088D01*
Y12750D02*
Y42088D01*
X176000Y43588D02*
Y44000D01*
X111000Y34588D02*
Y35000D01*
X107500Y31088D02*
X111000Y34588D01*
X107500Y12750D02*
Y31088D01*
X197500Y12750D02*
Y33000D01*
X152000Y36000D02*
X152500Y35500D01*
Y12750D02*
Y35500D01*
X137000Y36000D02*
X137500Y35500D01*
Y12750D02*
Y35500D01*
X122500Y34500D02*
X123000Y35000D01*
X122500Y12750D02*
Y34500D01*
X92500Y33500D02*
X93000Y34000D01*
X92500Y12750D02*
Y33500D01*
X27500Y12750D02*
Y29000D01*
X27000Y12750D02*
X27500D01*
X22500D02*
Y29000D01*
X17500Y12750D02*
Y27000D01*
D26*
X31000Y137250D02*
D03*
Y128750D02*
D03*
X42000Y137250D02*
D03*
Y128750D02*
D03*
X38000Y73250D02*
D03*
Y64750D02*
D03*
X80000Y73250D02*
D03*
Y64750D02*
D03*
D27*
X63000Y147701D02*
D03*
X69500Y132299D02*
D03*
D28*
X56500D02*
D03*
D29*
X85384Y138540D02*
D03*
Y153540D02*
D03*
D30*
X85523Y118856D02*
D03*
Y127856D02*
D03*
D31*
X124500Y106000D02*
D03*
X115500D02*
D03*
D32*
X39214Y360000D02*
D03*
X46786D02*
D03*
D33*
X17500Y12750D02*
D03*
X22500D02*
D03*
X27500D02*
D03*
X32500D02*
D03*
X37500D02*
D03*
X42500D02*
D03*
X47500D02*
D03*
X52500D02*
D03*
X57500D02*
D03*
X62500D02*
D03*
X67500D02*
D03*
X72500D02*
D03*
X77500D02*
D03*
X82500D02*
D03*
X87500D02*
D03*
X92500D02*
D03*
X97500D02*
D03*
X102500D02*
D03*
X107500D02*
D03*
X112500D02*
D03*
X117500D02*
D03*
X122500D02*
D03*
X127500D02*
D03*
X132500D02*
D03*
X137500D02*
D03*
X142500D02*
D03*
X147500D02*
D03*
X152500D02*
D03*
X187500D02*
D03*
X192500D02*
D03*
X197500D02*
D03*
X202500D02*
D03*
X182500D02*
D03*
X177500D02*
D03*
D34*
X102000Y136750D02*
D03*
Y129250D02*
D03*
X117000Y136750D02*
D03*
Y129250D02*
D03*
D35*
X185758Y96000D02*
D03*
X160242D02*
D03*
X185758Y119000D02*
D03*
X160242D02*
D03*
D36*
X121304Y346850D02*
D03*
Y365150D02*
D03*
X102000Y356000D02*
D03*
D37*
X59500Y344000D02*
D03*
X74500D02*
D03*
D38*
X170000Y340000D02*
D03*
X160000D02*
D03*
X95000Y324000D02*
D03*
X105000D02*
D03*
X160000Y360000D02*
D03*
X170000D02*
D03*
D39*
X127500Y88000D02*
D03*
X112500D02*
D03*
D40*
X70000Y360000D02*
D03*
X60000D02*
D03*
X179000Y160000D02*
D03*
X169000D02*
D03*
X179000Y148000D02*
D03*
X169000D02*
D03*
X179000Y136000D02*
D03*
X169000D02*
D03*
D41*
X39000Y348000D02*
D03*
Y338000D02*
D03*
D42*
X66000Y64000D02*
D03*
Y74000D02*
D03*
X52000Y64000D02*
D03*
Y74000D02*
D03*
X190000Y335000D02*
D03*
Y345000D02*
D03*
X141000Y361000D02*
D03*
Y351000D02*
D03*
D47*
X34000Y383750D02*
D03*
D48*
X19250Y399000D02*
D03*
X48750D02*
D03*
D61*
X33000Y144000D02*
G03*
X31000Y139172I4828J-4828D01*
G01*
X39000Y147000D02*
G03*
X33879Y144879I0J-7243D01*
G01*
X118000Y47000D02*
G03*
X117500Y45793I1207J-1207D01*
G01*
X125000Y94036D02*
G03*
X127500Y88000I8536J0D01*
G01*
X59500Y344000D02*
G03*
X60000Y345207I-1207J1207D01*
G01*
X34000Y372071D02*
G03*
X39000Y360000I17071J0D01*
G01*
X39000Y336485D02*
G03*
X45000Y322000I20485J0D01*
G01*
X50009Y309908D02*
G03*
X45000Y322000I-17100J0D01*
G01*
X42000Y137250D02*
X55690D01*
X56500Y132299D02*
Y136440D01*
X55690Y137250D02*
X56500Y136440D01*
X85523Y127856D02*
Y138400D01*
X85384Y138540D02*
X85523Y138400D01*
X63000Y147701D02*
Y150218D01*
X63671Y150889D01*
X71063D01*
X73714Y153540D01*
X85384D01*
X102000Y136750D02*
Y155000D01*
X113000Y166000D01*
X31000Y137250D02*
Y139172D01*
X33000Y144000D02*
X33879Y144879D01*
X31000Y137250D02*
X42000D01*
X31000Y123000D02*
X40000Y114000D01*
X31000Y123000D02*
Y128750D01*
X42000Y123000D02*
X50000Y115000D01*
X42000Y123000D02*
Y128750D01*
X117500Y12750D02*
Y45793D01*
X145000Y154000D02*
Y177007D01*
X145995Y178002D01*
X114048Y66436D02*
X125436D01*
X72000Y98000D02*
X82484D01*
X114048Y66436D01*
X66000Y92000D02*
X72000Y98000D01*
X66000Y74000D02*
Y92000D01*
X125436Y66436D02*
X138000Y79000D01*
Y145888D02*
X145000Y152888D01*
X138000Y79000D02*
Y145888D01*
X145000Y152888D02*
Y154000D01*
X52000Y103000D02*
X62000Y113000D01*
X52000Y74000D02*
Y103000D01*
X62000Y113000D02*
X122000D01*
X132000Y123000D01*
Y154000D01*
Y156191D02*
X134997Y159187D01*
Y178002D01*
X132000Y154000D02*
Y156191D01*
X125000Y94036D02*
Y106000D01*
X117000Y136750D02*
X125000D01*
X94000D02*
X102000D01*
X113000Y166000D02*
Y178002D01*
X117000Y136750D02*
Y154000D01*
X123999Y160999D01*
Y178002D01*
X113000Y318887D02*
X118000Y323887D01*
X113000Y299998D02*
Y318887D01*
X118000Y323887D02*
Y325000D01*
X108000D02*
X118000D01*
X107000Y324000D02*
X108000Y325000D01*
X92793Y354793D02*
X100793D01*
X102000Y356000D01*
X82000Y344000D02*
X92793Y354793D01*
X74500Y344000D02*
X82000D01*
X60000Y345207D02*
Y360000D01*
X47000D02*
X60000D01*
X39000D02*
X39000Y360000D01*
Y348000D02*
Y360000D01*
X34000Y372071D02*
Y383750D01*
X39000Y336485D02*
Y338000D01*
X50009Y299998D02*
Y309908D01*
X80000Y49000D02*
Y64750D01*
X45000Y49000D02*
X52000Y56000D01*
Y64000D01*
X56000Y45000D02*
X66000Y55000D01*
Y64000D01*
X38000Y54000D02*
Y64750D01*
X37500Y53500D02*
X38000Y54000D01*
X37500Y12750D02*
Y53500D01*
D62*
X187096Y13727D02*
G03*
X187500Y12750I1381J0D01*
G01*
X182500D02*
G03*
X182904Y13727I-976J976D01*
G01*
X187096D02*
Y64000D01*
X187096Y64000D01*
X127402Y310514D02*
Y317617D01*
X126793Y302792D02*
Y309905D01*
X127402Y310514D01*
X123999Y299998D02*
X126793Y302792D01*
X181031Y64000D02*
X181857Y63175D01*
Y61830D02*
Y63175D01*
Y61830D02*
X182904Y60783D01*
Y13727D02*
Y60783D01*
X131593Y310514D02*
Y317617D01*
X132203Y302792D02*
X134997Y299998D01*
X131593Y310514D02*
X132203Y309905D01*
Y302792D02*
Y309905D01*
D63*
X132000Y154000D02*
D03*
X177000Y323000D02*
D03*
X118000Y325000D02*
D03*
X150000Y327000D02*
D03*
X170000Y375000D02*
D03*
X201000Y301000D02*
D03*
X104000Y154000D02*
D03*
X118000D02*
D03*
X145000D02*
D03*
D64*
X113000Y299998D02*
D03*
X156993D02*
D03*
X167992D02*
D03*
X178990D02*
D03*
X123999D02*
D03*
X134997D02*
D03*
X145995D02*
D03*
X83003D02*
D03*
X50009D02*
D03*
X61007D02*
D03*
X72005D02*
D03*
X39010D02*
D03*
X72005Y178002D02*
D03*
X50009D02*
D03*
X39010D02*
D03*
X83003D02*
D03*
X61007D02*
D03*
X145995D02*
D03*
X134997D02*
D03*
X123999D02*
D03*
X178990D02*
D03*
X167992D02*
D03*
X156993D02*
D03*
X113000D02*
D03*
D65*
X69468Y121045D02*
D03*
X40000Y114000D02*
D03*
X50000Y115000D02*
D03*
X39000Y147000D02*
D03*
X118000Y47000D02*
D03*
X200000Y78350D02*
D03*
X207794Y79007D02*
D03*
X203112Y61996D02*
D03*
X211343Y71000D02*
D03*
X212000Y61000D02*
D03*
X63000Y38000D02*
D03*
X193000Y37000D02*
D03*
X208000Y193000D02*
D03*
X205000Y239000D02*
D03*
X206000Y215000D02*
D03*
Y259000D02*
D03*
Y268000D02*
D03*
Y276000D02*
D03*
X213640Y410220D02*
D03*
X209830Y402600D02*
D03*
X213640Y394980D02*
D03*
X209830Y387360D02*
D03*
X206020Y410220D02*
D03*
X202210Y402600D02*
D03*
X206020Y394980D02*
D03*
X202210Y387360D02*
D03*
Y174000D02*
D03*
Y158760D02*
D03*
Y143520D02*
D03*
X198400Y410220D02*
D03*
X194590Y402600D02*
D03*
X198400Y394980D02*
D03*
X194590Y387360D02*
D03*
X190780Y410220D02*
D03*
X186970Y402600D02*
D03*
X190780Y394980D02*
D03*
X186970Y387360D02*
D03*
X183160Y410220D02*
D03*
X179350Y402600D02*
D03*
X183160Y394980D02*
D03*
X179350Y387360D02*
D03*
X175540Y410220D02*
D03*
X171730Y402600D02*
D03*
X175540Y394980D02*
D03*
X171730Y387360D02*
D03*
X167920Y410220D02*
D03*
X164110Y402600D02*
D03*
X167920Y394980D02*
D03*
X164110Y387360D02*
D03*
X160300Y410220D02*
D03*
X156490Y402600D02*
D03*
X160300Y394980D02*
D03*
X156490Y387360D02*
D03*
X152680Y410220D02*
D03*
X148870Y402600D02*
D03*
X152680Y394980D02*
D03*
X148870Y387360D02*
D03*
X145060Y410220D02*
D03*
X141250Y402600D02*
D03*
X145060Y394980D02*
D03*
X141250Y387360D02*
D03*
X137440Y394980D02*
D03*
X133630Y387360D02*
D03*
X126010D02*
D03*
X110770Y372120D02*
D03*
X106960Y379740D02*
D03*
X103150Y372120D02*
D03*
X106960Y364500D02*
D03*
X103150Y341640D02*
D03*
X95530Y387360D02*
D03*
X99340Y379740D02*
D03*
X95530Y372120D02*
D03*
X99340Y364500D02*
D03*
X95530Y341640D02*
D03*
Y311160D02*
D03*
Y295920D02*
D03*
Y280680D02*
D03*
X87910Y387360D02*
D03*
X91720Y379740D02*
D03*
X87910Y372120D02*
D03*
X91720Y364500D02*
D03*
X87910Y341640D02*
D03*
Y326400D02*
D03*
X91720Y303540D02*
D03*
Y288300D02*
D03*
X87910Y280680D02*
D03*
X91720Y273060D02*
D03*
X87910Y265440D02*
D03*
X80290Y402600D02*
D03*
X84100Y394980D02*
D03*
X80290Y387360D02*
D03*
X84100Y379740D02*
D03*
X80290Y372120D02*
D03*
X84100Y364500D02*
D03*
Y334020D02*
D03*
X80290Y326400D02*
D03*
Y280680D02*
D03*
X84100Y273060D02*
D03*
X80290Y265440D02*
D03*
X76480Y410220D02*
D03*
X72670Y402600D02*
D03*
X76480Y394980D02*
D03*
X72670Y387360D02*
D03*
X76480Y379740D02*
D03*
X72670Y372120D02*
D03*
X76480Y334020D02*
D03*
X72670Y326400D02*
D03*
X76480Y318780D02*
D03*
Y273060D02*
D03*
X72670Y265440D02*
D03*
X68860Y410220D02*
D03*
X65050Y402600D02*
D03*
X68860Y394980D02*
D03*
X65050Y387360D02*
D03*
X68860Y379740D02*
D03*
X65050Y372120D02*
D03*
X68860Y334020D02*
D03*
X65050Y326400D02*
D03*
X68860Y318780D02*
D03*
Y273060D02*
D03*
X65050Y265440D02*
D03*
X61240Y379740D02*
D03*
X57430Y372120D02*
D03*
X61240Y334020D02*
D03*
X57430Y326400D02*
D03*
Y280680D02*
D03*
X53620Y379740D02*
D03*
X49810Y372120D02*
D03*
Y280680D02*
D03*
X42190D02*
D03*
X46000Y273060D02*
D03*
X42190Y265440D02*
D03*
X38380Y410220D02*
D03*
X34570Y402600D02*
D03*
Y280680D02*
D03*
X38380Y273060D02*
D03*
X34570Y265440D02*
D03*
X30760Y410220D02*
D03*
X26950Y326400D02*
D03*
X30760Y318780D02*
D03*
X26950Y311160D02*
D03*
X30760Y303540D02*
D03*
X26950Y295920D02*
D03*
X30760Y288300D02*
D03*
X26950Y280680D02*
D03*
X30760Y273060D02*
D03*
X26950Y265440D02*
D03*
X19330Y372120D02*
D03*
X23140Y364500D02*
D03*
X19330Y356880D02*
D03*
X23140Y349260D02*
D03*
X19330Y341640D02*
D03*
X23140Y334020D02*
D03*
X19330Y326400D02*
D03*
X23140Y318780D02*
D03*
X19330Y311160D02*
D03*
X23140Y303540D02*
D03*
X19330Y295920D02*
D03*
X23140Y288300D02*
D03*
X19330Y280680D02*
D03*
X23140Y273060D02*
D03*
X19330Y265440D02*
D03*
Y250200D02*
D03*
Y234960D02*
D03*
Y219720D02*
D03*
Y204480D02*
D03*
Y189240D02*
D03*
Y174000D02*
D03*
Y158760D02*
D03*
Y143520D02*
D03*
Y128280D02*
D03*
Y113040D02*
D03*
Y97800D02*
D03*
Y82560D02*
D03*
Y67320D02*
D03*
X15520Y379740D02*
D03*
X11710Y372120D02*
D03*
X15520Y364500D02*
D03*
X11710Y356880D02*
D03*
X15520Y349260D02*
D03*
X11710Y341640D02*
D03*
X15520Y334020D02*
D03*
X11710Y326400D02*
D03*
X15520Y318780D02*
D03*
X11710Y311160D02*
D03*
X15520Y303540D02*
D03*
X11710Y295920D02*
D03*
X15520Y288300D02*
D03*
X11710Y280680D02*
D03*
X15520Y273060D02*
D03*
X11710Y265440D02*
D03*
X15520Y257820D02*
D03*
X11710Y250200D02*
D03*
X15520Y242580D02*
D03*
X11710Y234960D02*
D03*
X15520Y227340D02*
D03*
X11710Y219720D02*
D03*
X15520Y212100D02*
D03*
X11710Y204480D02*
D03*
X15520Y196860D02*
D03*
X11710Y189240D02*
D03*
X15520Y181620D02*
D03*
X11710Y174000D02*
D03*
X15520Y166380D02*
D03*
X11710Y158760D02*
D03*
X15520Y151140D02*
D03*
X11710Y143520D02*
D03*
X15520Y135900D02*
D03*
X11710Y128280D02*
D03*
X15520Y120660D02*
D03*
X11710Y113040D02*
D03*
X15520Y105420D02*
D03*
X11710Y97800D02*
D03*
X15520Y90180D02*
D03*
X11710Y82560D02*
D03*
X15520Y74940D02*
D03*
X11710Y67320D02*
D03*
X15520Y59700D02*
D03*
X32151Y339810D02*
D03*
X31576Y332800D02*
D03*
X35076Y326800D02*
D03*
X38651Y320417D02*
D03*
X43408Y314602D02*
D03*
X55998Y314097D02*
D03*
X54580Y320095D02*
D03*
X50238Y325800D02*
D03*
X47228Y332057D02*
D03*
X46887Y338234D02*
D03*
X46651Y344528D02*
D03*
X41962Y367714D02*
D03*
X39820Y373823D02*
D03*
X31485Y353188D02*
D03*
X30909Y359800D02*
D03*
X29145Y365800D02*
D03*
X33000Y393477D02*
D03*
X23000Y383750D02*
D03*
X24523Y377500D02*
D03*
X28054Y371915D02*
D03*
X31719Y347000D02*
D03*
X46267Y350969D02*
D03*
X43782Y379467D02*
D03*
X41000Y393477D02*
D03*
X9000Y395000D02*
D03*
Y408000D02*
D03*
X62000Y394000D02*
D03*
X73000Y38000D02*
D03*
X187096Y64000D02*
D03*
X181031D02*
D03*
X78000Y86000D02*
D03*
X132530Y319000D02*
D03*
X126466D02*
D03*
X112000Y77000D02*
D03*
X106000Y106000D02*
D03*
X117000Y121000D02*
D03*
X102000Y119000D02*
D03*
X125000Y136750D02*
D03*
X94000D02*
D03*
X38000Y84000D02*
D03*
X83000Y317000D02*
D03*
X159000Y322000D02*
D03*
X50000Y161000D02*
D03*
X190000Y354000D02*
D03*
X177000Y340000D02*
D03*
X181000Y375000D02*
D03*
X145000Y368000D02*
D03*
X135000D02*
D03*
X95000Y334000D02*
D03*
X79000Y360000D02*
D03*
X39010Y160198D02*
D03*
X64425Y314602D02*
D03*
X36000Y314802D02*
D03*
X199000Y90000D02*
D03*
Y101000D02*
D03*
X198000Y117000D02*
D03*
Y126000D02*
D03*
X188000Y136000D02*
D03*
Y148000D02*
D03*
Y160000D02*
D03*
X159000Y152000D02*
D03*
Y145500D02*
D03*
Y139375D02*
D03*
X176000Y44000D02*
D03*
X195873Y44688D02*
D03*
X196187Y51172D02*
D03*
X111000Y35000D02*
D03*
X204114Y40000D02*
D03*
X203458Y48255D02*
D03*
X211000Y40000D02*
D03*
Y47870D02*
D03*
X152000Y36000D02*
D03*
X137000D02*
D03*
X123000Y35000D02*
D03*
X93000Y34000D02*
D03*
X33000Y31000D02*
D03*
Y38000D02*
D03*
X32880Y45166D02*
D03*
X33000Y51645D02*
D03*
X15000Y50312D02*
D03*
X12791Y42000D02*
D03*
X6395Y41971D02*
D03*
X6826Y50312D02*
D03*
X80000Y49000D02*
D03*
X45000D02*
D03*
X56000Y45000D02*
D03*
D66*
X110000Y420000D02*
D03*
M02*
